# BASEBOARD_FAB2 (Tioga Pass) — schematic netlist excerpt (pin names and nets, part order shuffled) for the footprints in the layout excerpt that follows; sources: Cadence DE-HDL packaged netlist, KiCad conversion of Wiwynn_Tioga_Pass_MB.brd

C1R8  CAP  0.22UF 16V 10% X7R  pkg 0402  page 106 : A = P3E_CPU0_PE3_OCP_TXP<3> ; B = P3E_OCP_CPU0_PE3_C_TXP<3>
C22W10  SC22U16V5MX-4-GP  20%  pkg SMD-BCG5  page 231 : \1\ = VR_FET_SW_P12V_STBY_PVPP_ABC ; \2\ = GND
FB2T7  HCB1608KF-800T30-GP  pkg DISCRET-G9  page 149 : \1\ = P1V15_AUX_BMC ; \2\ = VCC_A_1V1
C8U11  CAP  100UF 4V 20% X5R  pkg 0805  page 225 : A = PVDDQ_GHJ ; B = GND

(kicad_pcb
	(version 20260206)
	(generator "pcbnew")
	(generator_version "10.0")
	(general
		(thickness 1.6)
		(legacy_teardrops no)
	)
	(paper "A4")
	(title_block
		(title "Wiwynn_Tioga_Pass_MB.brd")
		(comment 1 "Tioga Pass / footprints 3587-3590 of 4770")
	)
	(layers
		(0 "F.Cu" signal "TOP")
		(4 "In1.Cu" signal "L2GND")
		(6 "In2.Cu" signal "L3")
		(8 "In3.Cu" signal "L4GND")
		(10 "In4.Cu" signal "L5")
		(12 "In5.Cu" signal "L6GND")
		(14 "In6.Cu" signal "L7VCC")
		(16 "In7.Cu" signal "L8VCC")
		(18 "In8.Cu" signal "L9GND")
		(20 "In9.Cu" signal "L10")
		(22 "In10.Cu" signal "L11GND")
		(24 "In11.Cu" signal "L12")
		(26 "In12.Cu" signal "L13GND")
		(2 "B.Cu" signal "BOTTOM")
		(9 "F.Adhes" user "F.Adhesive")
		(11 "B.Adhes" user "B.Adhesive")
		(13 "F.Paste" user "Package Geometry/Pastemask Top")
		(15 "B.Paste" user "Package Geometry/Pastemask Bottom")
		(5 "F.SilkS" user "Ref Des/Silkscreen Top")
		(7 "B.SilkS" user "Ref Des/Silkscreen Bottom")
		(1 "F.Mask" user "Board Geometry/Soldermask Top")
		(3 "B.Mask" user "Board Geometry/Soldermask Bottom")
		(17 "Dwgs.User" user "User.Drawings")
		(19 "Cmts.User" user "User.Comments")
		(21 "Eco1.User" user "User.Eco1")
		(23 "Eco2.User" user "User.Eco2")
		(25 "Edge.Cuts" user "Board Geometry/Outline")
		(27 "Margin" user)
		(31 "F.CrtYd" user "Package Geometry/Place Bound Top")
		(29 "B.CrtYd" user "Package Geometry/Place Bound Bottom")
		(35 "F.Fab" user "Ref Des/Assembly Top")
		(33 "B.Fab" user "Ref Des/Assembly Bottom")
	)
	(footprint ""
		(layer "B.Cu")
		(at 105.636568 3.81 90)
		(property "Reference" "C8U11"
			(at 0 0 90)
			(layer "B.SilkS")
			(hide yes)
			(effects
				(font
					(size 1.27 1.27)
				)
				(justify mirror)
			)
		)
		(property "Value" ""
			(at 0 0 90)
			(layer "B.Fab")
			(effects
				(font
					(size 1.27 1.27)
				)
				(justify mirror)
			)
		)
		(duplicate_pad_numbers_are_jumpers no)
		(fp_poly
			(pts
				(xy 0.7239 -0.2159) (xy -0.7239 -0.2159) (xy -0.7239 1.9939) (xy 0.7239 1.9939)
			)
			(stroke
				(width 0)
				(type default)
			)
			(fill no)
			(layer "B.CrtYd")
		)
		(fp_line
			(start 0.7239 -0.2159)
			(end 0.7239 1.9939)
			(stroke
				(width 0.1)
				(type default)
			)
			(layer "B.Fab")
		)
		(fp_line
			(start -0.7239 -0.2159)
			(end 0.7239 -0.2159)
			(stroke
				(width 0.1)
				(type default)
			)
			(layer "B.Fab")
		)
		(fp_line
			(start 0.7239 1.9939)
			(end -0.7239 1.9939)
			(stroke
				(width 0.1)
				(type default)
			)
			(layer "B.Fab")
		)
		(fp_line
			(start -0.7239 1.9939)
			(end -0.7239 -0.2159)
			(stroke
				(width 0.1)
				(type default)
			)
			(layer "B.Fab")
		)
		(pad "1" smd rect
			(at 0 0 270)
			(size 1.27 1.016)
			(layers "B.Cu" "B.Mask" "B.Paste")
			(net "PVDDQ_GHJ")
		)
		(pad "2" smd rect
			(at 0 1.778 270)
			(size 1.27 1.016)
			(layers "B.Cu" "B.Mask" "B.Paste")
			(net "GND")
		)
		(zone
			(layer "B.Cu")
			(hatch none 0.5)
			(connect_pads
				(clearance 0)
			)
			(min_thickness 0.25)
			(keepout
				(tracks not_allowed)
				(vias allowed)
				(pads allowed)
				(copperpour not_allowed)
				(footprints allowed)
			)
			(placement
				(enabled no)
				(sheetname "")
			)
			(fill
				(thermal_gap 0.5)
				(thermal_bridge_width 0.5)
				(island_removal_mode 0)
			)
			(polygon
				(pts
					(xy 106.144568 3.175) (xy 106.144568 4.445) (xy 106.906568 4.445) (xy 106.906568 3.175)
				)
			)
		)
	)
	(footprint ""
		(layer "B.Cu")
		(at 413.922972 -31.805372)
		(property "Reference" "FB2T7"
			(at 0 0 0)
			(layer "B.SilkS")
			(hide yes)
			(effects
				(font
					(size 1.27 1.27)
				)
				(justify mirror)
			)
		)
		(property "Value" "*"
			(at -0.0254 -2.8829 0)
			(unlocked yes)
			(layer "B.Fab")
			(hide yes)
			(effects
				(font
					(size 1.27 1.016)
					(thickness 0.1524)
				)
				(justify mirror)
			)
		)
		(property "Device Type" "HCB1608KF-800T30-GP_DISCRET-G9A"
			(at -0.0254 -4.4069 0)
			(unlocked yes)
			(layer "B.Fab")
			(hide yes)
			(effects
				(font
					(size 1.27 1.016)
					(thickness 0.1524)
				)
				(justify mirror)
			)
		)
		(duplicate_pad_numbers_are_jumpers no)
		(fp_line
			(start -0.254 0)
			(end 0.254 0)
			(stroke
				(width 0.2032)
				(type default)
			)
			(layer "B.SilkS")
		)
		(fp_rect
			(start 0.5842 1.3335)
			(end -0.5842 -1.3335)
			(stroke
				(width 0)
				(type default)
			)
			(fill no)
			(layer "B.CrtYd")
		)
		(fp_rect
			(start 0.5842 1.3335)
			(end -0.5842 -1.3335)
			(stroke
				(width 0)
				(type default)
			)
			(fill no)
			(layer "B.Fab")
		)
		(pad "1" smd custom
			(at 0 -0.762 180)
			(size 0.2159 0.2159)
			(layers "B.Cu" "B.Mask" "B.Paste")
			(net "P1V15_AUX_BMC")
			(options
				(clearance outline)
				(anchor circle)
			)
			(primitives
				(gr_poly
					(pts
						(arc
							(start -0.3302 0.4318)
							(mid -0.402042 0.402042)
							(end -0.4318 0.3302)
						)
						(arc
							(start -0.4318 -0.3302)
							(mid -0.402042 -0.402042)
							(end -0.3302 -0.4318)
						)
						(arc
							(start 0.3302 -0.4318)
							(mid 0.402042 -0.402042)
							(end 0.4318 -0.3302)
						)
						(arc
							(start 0.4318 0.3302)
							(mid 0.402042 0.402042)
							(end 0.3302 0.4318)
						)
					)
					(width 0)
					(fill yes)
				)
			)
		)
		(pad "2" smd custom
			(at 0 0.762 180)
			(size 0.2159 0.2159)
			(layers "B.Cu" "B.Mask" "B.Paste")
			(net "VCC_A_1V1")
			(options
				(clearance outline)
				(anchor circle)
			)
			(primitives
				(gr_poly
					(pts
						(arc
							(start -0.3302 0.4318)
							(mid -0.402042 0.402042)
							(end -0.4318 0.3302)
						)
						(arc
							(start -0.4318 -0.3302)
							(mid -0.402042 -0.402042)
							(end -0.3302 -0.4318)
						)
						(arc
							(start 0.3302 -0.4318)
							(mid 0.402042 -0.402042)
							(end 0.4318 -0.3302)
						)
						(arc
							(start 0.4318 0.3302)
							(mid 0.402042 0.402042)
							(end 0.3302 0.4318)
						)
					)
					(width 0)
					(fill yes)
				)
			)
		)
	)
	(footprint ""
		(layer "B.Cu")
		(at 352.305874 -24.727916 90)
		(property "Reference" "C22W10"
			(at 0 0 90)
			(layer "B.SilkS")
			(hide yes)
			(effects
				(font
					(size 1.27 1.27)
				)
				(justify mirror)
			)
		)
		(property "Value" "*"
			(at 0.0762 -6.2357 90)
			(unlocked yes)
			(layer "B.Fab")
			(hide yes)
			(effects
				(font
					(size 1.27 1.016)
					(thickness 0.1524)
				)
				(justify mirror)
			)
		)
		(property "Device Type" "SC22U16V5MX-4-GP_SMD-BCG5-SC22A"
			(at 0.0762 -8.2677 90)
			(unlocked yes)
			(layer "B.Fab")
			(hide yes)
			(effects
				(font
					(size 1.27 1.016)
					(thickness 0.1524)
				)
				(justify mirror)
			)
		)
		(duplicate_pad_numbers_are_jumpers no)
		(fp_line
			(start -0.635 0)
			(end 0.635 0)
			(stroke
				(width 0.508)
				(type default)
			)
			(layer "B.SilkS")
		)
		(fp_rect
			(start 0.9652 1.778)
			(end -0.9652 -1.778)
			(stroke
				(width 0)
				(type default)
			)
			(fill no)
			(layer "B.CrtYd")
		)
		(fp_poly
			(pts
				(xy 0.9652 -1.778) (xy -0.9652 -1.778) (xy -0.9652 1.778) (xy 0.9652 1.778)
			)
			(stroke
				(width 0)
				(type default)
			)
			(fill no)
			(layer "B.Fab")
		)
		(pad "1" smd rect
			(at 0 -0.9652 270)
			(size 1.397 1.143)
			(layers "B.Cu" "B.Mask" "B.Paste")
			(net "VR_FET_SW_P12V_STBY_PVPP_ABC")
		)
		(pad "2" smd rect
			(at 0 0.9652 270)
			(size 1.397 1.143)
			(layers "B.Cu" "B.Mask" "B.Paste")
			(net "GND")
		)
	)
	(footprint ""
		(layer "B.Cu")
		(at 453.2122 -52.330858)
		(property "Reference" "C1R8"
			(at 0 0 0)
			(layer "B.SilkS")
			(hide yes)
			(effects
				(font
					(size 1.27 1.27)
				)
				(justify mirror)
			)
		)
		(property "Value" ""
			(at 0 0 0)
			(layer "B.Fab")
			(effects
				(font
					(size 1.27 1.27)
				)
				(justify mirror)
			)
		)
		(duplicate_pad_numbers_are_jumpers no)
		(fp_poly
			(pts
				(xy -0.3048 -0.1016) (xy -0.3048 0.9906) (xy 0.3048 0.9906) (xy 0.3048 -0.1016)
			)
			(stroke
				(width 0)
				(type default)
			)
			(fill no)
			(layer "B.CrtYd")
		)
		(fp_line
			(start -0.3048 -0.1016)
			(end 0.3048 -0.1016)
			(stroke
				(width 0.1)
				(type default)
			)
			(layer "B.Fab")
		)
		(fp_line
			(start -0.3048 0.9906)
			(end -0.3048 -0.1016)
			(stroke
				(width 0.1)
				(type default)
			)
			(layer "B.Fab")
		)
		(fp_line
			(start 0.3048 -0.1016)
			(end 0.3048 0.9906)
			(stroke
				(width 0.1)
				(type default)
			)
			(layer "B.Fab")
		)
		(fp_line
			(start 0.3048 0.9906)
			(end -0.3048 0.9906)
			(stroke
				(width 0.1)
				(type default)
			)
			(layer "B.Fab")
		)
		(pad "1" smd rect
			(at 0 0 180)
			(size 0.508 0.508)
			(layers "B.Cu" "B.Mask" "B.Paste")
			(net "P3E_CPU0_PE3_OCP_TXP<3>")
		)
		(pad "2" smd rect
			(at 0 0.889 180)
			(size 0.508 0.508)
			(layers "B.Cu" "B.Mask" "B.Paste")
			(net "P3E_OCP_CPU0_PE3_C_TXP<3>")
		)
		(zone
			(layer "B.Cu")
			(hatch none 0.5)
			(connect_pads
				(clearance 0)
			)
			(min_thickness 0.25)
			(keepout
				(tracks allowed)
				(vias not_allowed)
				(pads allowed)
				(copperpour not_allowed)
				(footprints allowed)
			)
			(placement
				(enabled no)
				(sheetname "")
			)
			(fill
				(thermal_gap 0.5)
				(thermal_bridge_width 0.5)
				(island_removal_mode 0)
			)
			(polygon
				(pts
					(xy 453.4662 -52.076858) (xy 452.9582 -52.076858) (xy 452.9582 -51.695858) (xy 453.4662 -51.695858)
				)
			)
		)
	)
)
